(kicad_pcb
	(version 20260206)
	(generator "pcbnew")
	(generator_version "10.0")
	(general
		(thickness 1.6)
		(legacy_teardrops no)
	)
	(paper "A4")
	(title_block
		(title "pdpb — Lightning_PDPB_BRD.brd")
		(comment 1 "Lightning (Wiwynn / Facebook NVMe JBOF) / footprints 157-157 of 1140")
	)
	(layers
		(0 "F.Cu" signal "TOP")
		(4 "In1.Cu" signal "L2GND")
		(6 "In2.Cu" signal "L3")
		(8 "In3.Cu" signal "L4VCC")
		(10 "In4.Cu" signal "L5VCC")
		(12 "In5.Cu" signal "L6")
		(14 "In6.Cu" signal "L7GND")
		(2 "B.Cu" signal "BOTTOM")
		(9 "F.Adhes" user "F.Adhesive")
		(11 "B.Adhes" user "B.Adhesive")
		(13 "F.Paste" user "Package Geometry/Pastemask Top")
		(15 "B.Paste" user "Package Geometry/Pastemask Bottom")
		(5 "F.SilkS" user "Ref Des/Silkscreen Top")
		(7 "B.SilkS" user "Ref Des/Silkscreen Bottom")
		(1 "F.Mask" user "Board Geometry/Soldermask Top")
		(3 "B.Mask" user "Board Geometry/Soldermask Bottom")
		(17 "Dwgs.User" user "User.Drawings")
		(19 "Cmts.User" user "User.Comments")
		(21 "Eco1.User" user "User.Eco1")
		(23 "Eco2.User" user "User.Eco2")
		(25 "Edge.Cuts" user "Board Geometry/Outline")
		(27 "Margin" user)
		(31 "F.CrtYd" user "Package Geometry/Place Bound Top")
		(29 "B.CrtYd" user "Package Geometry/Place Bound Bottom")
		(35 "F.Fab" user "Ref Des/Assembly Top")
		(33 "B.Fab" user "Ref Des/Assembly Bottom")
	)
	(footprint ""
		(layer "F.Cu")
		(at 226.149916 -67.669918 90)
		(property "Reference" "J4"
			(at 0 0 90)
			(layer "F.SilkS")
			(hide yes)
			(effects
				(font
					(size 1.27 1.27)
				)
			)
		)
		(property "Value" "PCISLT68-14-GP-U1"
			(at -22.225 12.7508 90)
			(unlocked yes)
			(layer "F.Fab")
			(hide yes)
			(effects
				(font
					(size 1.016 1.016)
					(thickness 0.1524)
				)
			)
		)
		(property "Device Type" "SD-78827-0001"
			(at -22.225 11.2268 90)
			(unlocked yes)
			(layer "F.Fab")
			(hide yes)
			(effects
				(font
					(size 1.016 1.016)
					(thickness 0.1524)
				)
			)
		)
		(duplicate_pad_numbers_are_jumpers no)
		(fp_line
			(start 20.4724 -3.4036)
			(end 20.4724 0.0254)
			(stroke
				(width 0.1524)
				(type default)
			)
			(layer "F.SilkS")
		)
		(fp_line
			(start -20.4724 -3.4036)
			(end 20.4724 -3.4036)
			(stroke
				(width 0.1524)
				(type default)
			)
			(layer "F.SilkS")
		)
		(fp_line
			(start 23.749 0.0254)
			(end 23.749 4.6736)
			(stroke
				(width 0.1524)
				(type default)
			)
			(layer "F.SilkS")
		)
		(fp_line
			(start 20.4724 0.0254)
			(end 23.749 0.0254)
			(stroke
				(width 0.1524)
				(type default)
			)
			(layer "F.SilkS")
		)
		(fp_line
			(start -20.4724 0.0254)
			(end -20.4724 -3.4036)
			(stroke
				(width 0.1524)
				(type default)
			)
			(layer "F.SilkS")
		)
		(fp_line
			(start -23.749 0.0254)
			(end -20.4724 0.0254)
			(stroke
				(width 0.1524)
				(type default)
			)
			(layer "F.SilkS")
		)
		(fp_line
			(start 23.117556 1.803908)
			(end 23.117556 2.896108)
			(stroke
				(width 0.3048)
				(type default)
			)
			(layer "F.SilkS")
		)
		(fp_line
			(start -20.882356 1.803908)
			(end -20.882356 2.896108)
			(stroke
				(width 0.3048)
				(type default)
			)
			(layer "F.SilkS")
		)
		(fp_line
			(start 20.882356 2.896108)
			(end 20.882356 1.803908)
			(stroke
				(width 0.3048)
				(type default)
			)
			(layer "F.SilkS")
		)
		(fp_line
			(start -23.117556 2.896108)
			(end -23.117556 1.803908)
			(stroke
				(width 0.3048)
				(type default)
			)
			(layer "F.SilkS")
		)
		(fp_line
			(start 23.749 4.6736)
			(end 20.4724 4.6736)
			(stroke
				(width 0.1524)
				(type default)
			)
			(layer "F.SilkS")
		)
		(fp_line
			(start 20.4724 4.6736)
			(end 20.4724 12.0142)
			(stroke
				(width 0.1524)
				(type default)
			)
			(layer "F.SilkS")
		)
		(fp_line
			(start -20.4724 4.6736)
			(end -23.749 4.6736)
			(stroke
				(width 0.1524)
				(type default)
			)
			(layer "F.SilkS")
		)
		(fp_line
			(start -23.749 4.6736)
			(end -23.749 0.0254)
			(stroke
				(width 0.1524)
				(type default)
			)
			(layer "F.SilkS")
		)
		(fp_line
			(start 17.8435 10.3124)
			(end -17.8435 10.3124)
			(stroke
				(width 0.1524)
				(type default)
			)
			(layer "F.SilkS")
		)
		(fp_line
			(start -17.8435 10.3124)
			(end -17.8435 12.0142)
			(stroke
				(width 0.1524)
				(type default)
			)
			(layer "F.SilkS")
		)
		(fp_line
			(start 20.4724 12.0142)
			(end 17.8435 12.0142)
			(stroke
				(width 0.1524)
				(type default)
			)
			(layer "F.SilkS")
		)
		(fp_line
			(start 17.8435 12.0142)
			(end 17.8435 10.3124)
			(stroke
				(width 0.1524)
				(type default)
			)
			(layer "F.SilkS")
		)
		(fp_line
			(start -17.8435 12.0142)
			(end -20.4724 12.0142)
			(stroke
				(width 0.1524)
				(type default)
			)
			(layer "F.SilkS")
		)
		(fp_line
			(start -20.4724 12.0142)
			(end -20.4724 4.6736)
			(stroke
				(width 0.1524)
				(type default)
			)
			(layer "F.SilkS")
		)
		(fp_arc
			(start 20.882356 1.803908)
			(mid 21.999956 0.686308)
			(end 23.117556 1.803908)
			(stroke
				(width 0.3048)
				(type default)
			)
			(layer "F.SilkS")
		)
		(fp_arc
			(start -23.117556 1.803908)
			(mid -21.999956 0.686308)
			(end -20.882356 1.803908)
			(stroke
				(width 0.3048)
				(type default)
			)
			(layer "F.SilkS")
		)
		(fp_arc
			(start 23.117556 2.896108)
			(mid 21.999956 4.013708)
			(end 20.882356 2.896108)
			(stroke
				(width 0.3048)
				(type default)
			)
			(layer "F.SilkS")
		)
		(fp_arc
			(start -20.882356 2.896108)
			(mid -21.999956 4.013708)
			(end -23.117556 2.896108)
			(stroke
				(width 0.3048)
				(type default)
			)
			(layer "F.SilkS")
		)
		(fp_poly
			(pts
				(xy -20.2184 11.7602) (xy -20.2184 4.4196) (xy -23.495 4.4196) (xy -23.495 0.2794) (xy -20.2184 0.2794)
				(xy -20.2184 -3.1496) (xy 20.2184 -3.1496) (xy 20.2184 0.2794) (xy 23.495 0.2794) (xy 23.495 4.4196)
				(xy 20.2184 4.4196) (xy 20.2184 11.7602) (xy 18.0975 11.7602) (xy 18.0975 10.0584) (xy -18.0975 10.0584)
				(xy -18.0975 11.7602)
			)
			(stroke
				(width 0)
				(type default)
			)
			(fill no)
			(layer "F.CrtYd")
		)
		(fp_poly
			(pts
				(xy -21.2471 16.256) (xy -21.2471 4.9276) (xy -24.003 4.9276) (xy -24.003 -0.2286) (xy -20.7264 -0.2286)
				(xy -20.7264 -3.6576) (xy 20.7264 -3.6576) (xy 20.7264 -0.2286) (xy 24.003 -0.2286) (xy 24.003 -0.00635)
				(xy 20.2184 -0.00635) (xy 20.2184 -3.1496) (xy -20.2184 -3.1496) (xy -20.2184 0.2794) (xy -23.495 0.2794)
				(xy -23.495 4.4196) (xy -20.2184 4.4196) (xy -20.2184 11.7602) (xy -18.0975 11.7602) (xy -18.0975 10.0584)
				(xy 18.0975 10.0584) (xy 18.0975 11.7602) (xy 20.2184 11.7602) (xy 20.2184 4.4196) (xy 23.495 4.4196)
				(xy 23.495 0.2794) (xy 20.2184 0.2794) (xy 20.2184 0.00635) (xy 24.003 0.00635) (xy 24.003 4.9276)
				(xy 21.2471 4.9276) (xy 21.2471 16.256)
			)
			(stroke
				(width 0)
				(type default)
			)
			(fill no)
			(layer "F.CrtYd")
		)
		(fp_poly
			(pts
				(xy -21.2471 16.256) (xy -21.2471 4.9276) (xy -24.003 4.9276) (xy -24.003 -0.2286) (xy -20.7264 -0.2286)
				(xy -20.7264 -3.6576) (xy 20.7264 -3.6576) (xy 20.7264 -0.2286) (xy 24.003 -0.2286) (xy 24.003 4.9276)
				(xy 21.2471 4.9276) (xy 21.2471 16.256)
			)
			(stroke
				(width 0)
				(type default)
			)
			(fill no)
			(layer "F.Fab")
		)
		(pad "" np_thru_hole circle
			(at -18.999962 0 90)
			(size 0.254 0.254)
			(drill 1.8542)
			(layers "*.Cu" "*.Mask")
			(clearance 1.1557)
			(thermal_gap 1.1557)
		)
		(pad "" np_thru_hole circle
			(at 18.999962 0 90)
			(size 0.254 0.254)
			(drill 1.8542)
			(layers "*.Cu" "*.Mask")
			(clearance 1.1557)
			(thermal_gap 1.1557)
		)
		(pad "E1" smd rect
			(at -7.079996 1.240028 90)
			(size 0.508 2.0066)
			(layers "F.Cu" "F.Mask" "F.Paste")
			(net "PE_CLK100M_DR4_2_P")
		)
		(pad "E2" smd rect
			(at -6.279896 1.240028 90)
			(size 0.508 2.0066)
			(layers "F.Cu" "F.Mask" "F.Paste")
			(net "PE_CLK100M_DR4_2_N")
		)
		(pad "E3" smd rect
			(at -5.48005 1.240028 90)
			(size 0.508 2.0066)
			(layers "F.Cu" "F.Mask" "F.Paste")
			(net "P3V3")
		)
		(pad "E4" smd rect
			(at -4.67995 1.240028 90)
			(size 0.508 2.0066)
			(layers "F.Cu" "F.Mask" "F.Paste")
			(net "SSD4_PERST_N")
		)
		(pad "E5" smd rect
			(at -3.880104 1.240028 90)
			(size 0.508 2.0066)
			(layers "F.Cu" "F.Mask" "F.Paste")
			(net "SSD4_PERST_N")
		)
		(pad "E6" smd rect
			(at -3.080004 1.240028 90)
			(size 0.508 2.0066)
			(layers "F.Cu" "F.Mask" "F.Paste")
			(net "Net_1161")
		)
		(pad "E7" smd rect
			(at -15.48003 -1.949958 90)
			(size 0.508 2.0066)
			(layers "F.Cu" "F.Mask" "F.Paste")
			(net "PE_CLK100M_DR4_1_P")
		)
		(pad "E8" smd rect
			(at -14.67993 -1.949958 90)
			(size 0.508 2.0066)
			(layers "F.Cu" "F.Mask" "F.Paste")
			(net "PE_CLK100M_DR4_1_N")
		)
		(pad "E9" smd rect
			(at -13.880084 -1.949958 90)
			(size 0.508 2.0066)
			(layers "F.Cu" "F.Mask" "F.Paste")
			(net "GND")
		)
		(pad "E10" smd rect
			(at -13.079984 -1.949958 90)
			(size 0.508 2.0066)
			(layers "F.Cu" "F.Mask" "F.Paste")
			(net "PE_TX1_DR4_N")
		)
		(pad "E11" smd rect
			(at -12.279884 -1.949958 90)
			(size 0.508 2.0066)
			(layers "F.Cu" "F.Mask" "F.Paste")
			(net "PE_TX1_DR4_P")
		)
		(pad "E12" smd rect
			(at -11.480038 -1.949958 90)
			(size 0.508 2.0066)
			(layers "F.Cu" "F.Mask" "F.Paste")
			(net "GND")
		)
		(pad "E13" smd rect
			(at -10.679938 -1.949958 90)
			(size 0.508 2.0066)
			(layers "F.Cu" "F.Mask" "F.Paste")
			(net "PE_RX1_DR4_N")
		)
		(pad "E14" smd rect
			(at -9.880092 -1.949958 90)
			(size 0.508 2.0066)
			(layers "F.Cu" "F.Mask" "F.Paste")
			(net "PE_RX1_DR4_P")
		)
		(pad "E15" smd rect
			(at -9.079992 -1.949958 90)
			(size 0.508 2.0066)
			(layers "F.Cu" "F.Mask" "F.Paste")
			(net "GND")
		)
		(pad "E16" smd rect
			(at -8.279892 -1.949958 90)
			(size 0.508 2.0066)
			(layers "F.Cu" "F.Mask" "F.Paste")
			(net "Net_1168")
		)
		(pad "E17" smd rect
			(at 9.320022 -1.949958 90)
			(size 0.508 2.0066)
			(layers "F.Cu" "F.Mask" "F.Paste")
			(net "PE_TX4_DR4_N")
		)
		(pad "E18" smd rect
			(at 10.120122 -1.949958 90)
			(size 0.508 2.0066)
			(layers "F.Cu" "F.Mask" "F.Paste")
			(net "PE_TX4_DR4_P")
		)
		(pad "E19" smd rect
			(at 10.919968 -1.949958 90)
			(size 0.508 2.0066)
			(layers "F.Cu" "F.Mask" "F.Paste")
			(net "GND")
		)
		(pad "E20" smd rect
			(at 11.720068 -1.949958 90)
			(size 0.508 2.0066)
			(layers "F.Cu" "F.Mask" "F.Paste")
			(net "PE_RX4_DR4_N")
		)
		(pad "E21" smd rect
			(at 12.519914 -1.949958 90)
			(size 0.508 2.0066)
			(layers "F.Cu" "F.Mask" "F.Paste")
			(net "PE_RX4_DR4_P")
		)
		(pad "E22" smd rect
			(at 13.320014 -1.949958 90)
			(size 0.508 2.0066)
			(layers "F.Cu" "F.Mask" "F.Paste")
			(net "GND")
		)
		(pad "E23" smd rect
			(at 14.120114 -1.949958 90)
			(size 0.508 2.0066)
			(layers "F.Cu" "F.Mask" "F.Paste")
			(net "SCL_DR4_R")
		)
		(pad "E24" smd rect
			(at 14.91996 -1.949958 90)
			(size 0.508 2.0066)
			(layers "F.Cu" "F.Mask" "F.Paste")
			(net "SDA_DR4_R")
		)
		(pad "E25" smd rect
			(at 15.72006 -1.949958 90)
			(size 0.508 2.0066)
			(layers "F.Cu" "F.Mask" "F.Paste")
			(net "DUALPORTEN#4")
		)
		(pad "P1" smd rect
			(at -1.905 0.824992 90)
			(size 0.6604 2.0574)
			(layers "F.Cu" "F.Mask" "F.Paste")
			(net "Net_1164")
		)
		(pad "P2" smd rect
			(at -0.635 0.824992 90)
			(size 0.6604 2.0574)
			(layers "F.Cu" "F.Mask" "F.Paste")
			(net "Net_1163")
		)
		(pad "P3" smd rect
			(at 0.635 0.824992 90)
			(size 0.6604 2.0574)
			(layers "F.Cu" "F.Mask" "F.Paste")
			(net "Net_1162")
		)
		(pad "P4" smd rect
			(at 1.905 0.824992 90)
			(size 0.6604 2.0574)
			(layers "F.Cu" "F.Mask" "F.Paste")
			(net "SSD4_CLK0_OE_N")
		)
		(pad "P5" smd rect
			(at 3.175 0.824992 90)
			(size 0.6604 2.0574)
			(layers "F.Cu" "F.Mask" "F.Paste")
			(net "GND")
		)
		(pad "P6" smd rect
			(at 4.445 0.824992 90)
			(size 0.6604 2.0574)
			(layers "F.Cu" "F.Mask" "F.Paste")
			(net "GND")
		)
		(pad "P7" smd rect
			(at 5.715 0.824992 90)
			(size 0.6604 2.0574)
			(layers "F.Cu" "F.Mask" "F.Paste")
			(net "Net_91")
		)
		(pad "P8" smd rect
			(at 6.985 0.824992 90)
			(size 0.6604 2.0574)
			(layers "F.Cu" "F.Mask" "F.Paste")
			(net "Net_63")
		)
		(pad "P9" smd rect
			(at 8.255 0.824992 90)
			(size 0.6604 2.0574)
			(layers "F.Cu" "F.Mask" "F.Paste")
			(net "Net_77")
		)
		(pad "P10" smd rect
			(at 9.525 0.824992 90)
			(size 0.6604 2.0574)
			(layers "F.Cu" "F.Mask" "F.Paste")
			(net "SSD_PRSNT_NET4")
		)
		(pad "P11" smd rect
			(at 10.795 0.824992 90)
			(size 0.6604 2.0574)
			(layers "F.Cu" "F.Mask" "F.Paste")
			(net "SSD_ACT_DR4")
		)
		(pad "P12" smd rect
			(at 12.065 0.824992 90)
			(size 0.6604 2.0574)
			(layers "F.Cu" "F.Mask" "F.Paste")
			(net "GND")
		)
		(pad "P13" smd rect
			(at 13.335 0.824992 90)
			(size 0.6604 2.0574)
			(layers "F.Cu" "F.Mask" "F.Paste")
			(net "12V_PRECH_SSD4")
		)
		(pad "P14" smd rect
			(at 14.605 0.824992 90)
			(size 0.6604 2.0574)
			(layers "F.Cu" "F.Mask" "F.Paste")
			(net "P12V_SSD4")
		)
		(pad "P15" smd rect
			(at 15.875 0.824992 90)
			(size 0.6604 2.0574)
			(layers "F.Cu" "F.Mask" "F.Paste")
			(net "P12V_SSD4")
		)
		(pad "PTH1" thru_hole oval
			(at -21.999956 2.350008 90)
			(size 1.524 2.6162)
			(drill oval 0.8128 1.905)
			(layers "*.Cu" "*.Mask")
			(remove_unused_layers no)
			(net "Net_1173")
			(clearance 0.1524)
			(thermal_gap 0.1524)
		)
		(pad "PTH2" thru_hole oval
			(at 21.999956 2.350008 90)
			(size 1.524 2.6162)
			(drill oval 0.8128 1.905)
			(layers "*.Cu" "*.Mask")
			(remove_unused_layers no)
			(net "Net_1157")
			(clearance 0.1524)
			(thermal_gap 0.1524)
		)
		(pad "S1" smd rect
			(at -15.875 0.824992 90)
			(size 0.6604 2.0574)
			(layers "F.Cu" "F.Mask" "F.Paste")
			(net "GND")
		)
		(pad "S2" smd rect
			(at -14.605 0.824992 90)
			(size 0.6604 2.0574)
			(layers "F.Cu" "F.Mask" "F.Paste")
			(net "Net_1172")
		)
		(pad "S3" smd rect
			(at -13.335 0.824992 90)
			(size 0.6604 2.0574)
			(layers "F.Cu" "F.Mask" "F.Paste")
			(net "Net_1171")
		)
		(pad "S4" smd rect
			(at -12.065 0.824992 90)
			(size 0.6604 2.0574)
			(layers "F.Cu" "F.Mask" "F.Paste")
			(net "GND")
		)
		(pad "S5" smd rect
			(at -10.795 0.824992 90)
			(size 0.6604 2.0574)
			(layers "F.Cu" "F.Mask" "F.Paste")
			(net "Net_1170")
		)
		(pad "S6" smd rect
			(at -9.525 0.824992 90)
			(size 0.6604 2.0574)
			(layers "F.Cu" "F.Mask" "F.Paste")
			(net "Net_1169")
		)
		(pad "S7" smd rect
			(at -8.255 0.824992 90)
			(size 0.6604 2.0574)
			(layers "F.Cu" "F.Mask" "F.Paste")
			(net "GND")
		)
		(pad "S8" smd rect
			(at -7.480046 -1.949958 90)
			(size 0.508 2.0066)
			(layers "F.Cu" "F.Mask" "F.Paste")
			(net "GND")
		)
		(pad "S9" smd rect
			(at -6.679946 -1.949958 90)
			(size 0.508 2.0066)
			(layers "F.Cu" "F.Mask" "F.Paste")
			(net "Net_1167")
		)
		(pad "S10" smd rect
			(at -5.8801 -1.949958 90)
			(size 0.508 2.0066)
			(layers "F.Cu" "F.Mask" "F.Paste")
			(net "Net_1166")
		)
		(pad "S11" smd rect
			(at -5.08 -1.949958 90)
			(size 0.508 2.0066)
			(layers "F.Cu" "F.Mask" "F.Paste")
			(net "GND")
		)
		(pad "S12" smd rect
			(at -4.2799 -1.949958 90)
			(size 0.508 2.0066)
			(layers "F.Cu" "F.Mask" "F.Paste")
			(net "Net_1165")
		)
		(pad "S13" smd rect
			(at -3.480054 -1.949958 90)
			(size 0.508 2.0066)
			(layers "F.Cu" "F.Mask" "F.Paste")
			(net "Net_1160")
		)
		(pad "S14" smd rect
			(at -2.679954 -1.949958 90)
			(size 0.508 2.0066)
			(layers "F.Cu" "F.Mask" "F.Paste")
			(net "GND")
		)
		(pad "S15" smd rect
			(at -1.880108 -1.949958 90)
			(size 0.508 2.0066)
			(layers "F.Cu" "F.Mask" "F.Paste")
			(net "Net_1159")
		)
		(pad "S16" smd rect
			(at -1.080008 -1.949958 90)
			(size 0.508 2.0066)
			(layers "F.Cu" "F.Mask" "F.Paste")
			(net "GND")
		)
		(pad "S17" smd rect
			(at -0.279908 -1.949958 90)
			(size 0.508 2.0066)
			(layers "F.Cu" "F.Mask" "F.Paste")
			(net "PE_TX2_DR4_N")
		)
		(pad "S18" smd rect
			(at 0.519938 -1.949958 90)
			(size 0.508 2.0066)
			(layers "F.Cu" "F.Mask" "F.Paste")
			(net "PE_TX2_DR4_P")
		)
		(pad "S19" smd rect
			(at 1.320038 -1.949958 90)
			(size 0.508 2.0066)
			(layers "F.Cu" "F.Mask" "F.Paste")
			(net "GND")
		)
		(pad "S20" smd rect
			(at 2.119884 -1.949958 90)
			(size 0.508 2.0066)
			(layers "F.Cu" "F.Mask" "F.Paste")
			(net "PE_RX2_DR4_N")
		)
		(pad "S21" smd rect
			(at 2.919984 -1.949958 90)
			(size 0.508 2.0066)
			(layers "F.Cu" "F.Mask" "F.Paste")
			(net "PE_RX2_DR4_P")
		)
		(pad "S22" smd rect
			(at 3.720084 -1.949958 90)
			(size 0.508 2.0066)
			(layers "F.Cu" "F.Mask" "F.Paste")
			(net "GND")
		)
		(pad "S23" smd rect
			(at 4.51993 -1.949958 90)
			(size 0.508 2.0066)
			(layers "F.Cu" "F.Mask" "F.Paste")
			(net "PE_TX3_DR4_N")
		)
		(pad "S24" smd rect
			(at 5.32003 -1.949958 90)
			(size 0.508 2.0066)
			(layers "F.Cu" "F.Mask" "F.Paste")
			(net "PE_TX3_DR4_P")
		)
		(pad "S25" smd rect
			(at 6.119876 -1.949958 90)
			(size 0.508 2.0066)
			(layers "F.Cu" "F.Mask" "F.Paste")
			(net "GND")
		)
		(pad "S26" smd rect
			(at 6.919976 -1.949958 90)
			(size 0.508 2.0066)
			(layers "F.Cu" "F.Mask" "F.Paste")
			(net "PE_RX3_DR4_N")
		)
		(pad "S27" smd rect
			(at 7.720076 -1.949958 90)
			(size 0.508 2.0066)
			(layers "F.Cu" "F.Mask" "F.Paste")
			(net "PE_RX3_DR4_P")
		)
		(pad "S28" smd rect
			(at 8.519922 -1.949958 90)
			(size 0.508 2.0066)
			(layers "F.Cu" "F.Mask" "F.Paste")
			(net "GND")
		)
		(zone
			(layers "F.Cu" "B.Cu" "In1.Cu" "In2.Cu" "In3.Cu" "In4.Cu" "In5.Cu" "In6.Cu")
			(hatch none 0.5)
			(connect_pads
				(clearance 0)
			)
			(min_thickness 0.25)
			(keepout
				(tracks not_allowed)
				(vias allowed)
				(pads allowed)
				(copperpour not_allowed)
				(footprints allowed)
			)
			(placement
				(enabled no)
				(sheetname "")
			)
			(fill
				(thermal_gap 0.5)
				(thermal_bridge_width 0.5)
				(island_removal_mode 0)
			)
			(polygon
				(pts
					(arc
						(start 227.381816 -86.66988)
						(mid 224.918016 -86.66988)
						(end 227.381816 -86.66988)
					)
				)
			)
		)
		(zone
			(layers "F.Cu" "B.Cu" "In1.Cu" "In2.Cu" "In3.Cu" "In4.Cu" "In5.Cu" "In6.Cu")
			(hatch none 0.5)
			(connect_pads
				(clearance 0)
			)
			(min_thickness 0.25)
			(keepout
				(tracks not_allowed)
				(vias allowed)
				(pads allowed)
				(copperpour not_allowed)
				(footprints allowed)
			)
			(placement
				(enabled no)
				(sheetname "")
			)
			(fill
				(thermal_gap 0.5)
				(thermal_bridge_width 0.5)
				(island_removal_mode 0)
			)
			(polygon
				(pts
					(arc
						(start 227.381816 -48.669956)
						(mid 224.918016 -48.669956)
						(end 227.381816 -48.669956)
					)
				)
			)
		)
	)
)
